# S9S_MB_2U (Grand Teton) — schematic netlist excerpt (pin names and nets, part order shuffled) for the footprints in the layout excerpt that follows; sources: Cadence DE-HDL packaged netlist, KiCad conversion of 03242023_DA0F0TMBIJ0_F0T_Motherboard_J_brd_V01_OCP.brd

U290  MOSFET_NCH_GDS_ESD_PROTECTED  2N7002K IC  pkg SOT23_GDSXC  page 301
  D  = HSC_EN
  G  = PDB_PRSNT_N
  S  = GND

(kicad_pcb
	(version 20260206)
	(generator "pcbnew")
	(generator_version "10.0")
	(general
		(thickness 1.6)
		(legacy_teardrops no)
	)
	(paper "A4")
	(title_block
		(title "03242023_DA0F0TMBIJ0_F0T_Motherboard_J_brd_V01_OCP.brd")
		(comment 1 "Grand Teton / footprints 64-64 of 6105")
	)
	(layers
		(0 "F.Cu" signal "TOP")
		(4 "In1.Cu" signal "GND")
		(6 "In2.Cu" signal "IN1")
		(8 "In3.Cu" signal "GND1")
		(10 "In4.Cu" signal "IN2")
		(12 "In5.Cu" signal "GND2")
		(14 "In6.Cu" signal "IN3")
		(16 "In7.Cu" signal "GND3")
		(18 "In8.Cu" signal "VCC")
		(20 "In9.Cu" signal "VCC1")
		(22 "In10.Cu" signal "GND4")
		(24 "In11.Cu" signal "IN4")
		(26 "In12.Cu" signal "GND5")
		(28 "In13.Cu" signal "IN5")
		(30 "In14.Cu" signal "GND6")
		(32 "In15.Cu" signal "IN6")
		(34 "In16.Cu" signal "GND7")
		(2 "B.Cu" signal "BOTTOM")
		(9 "F.Adhes" user "F.Adhesive")
		(11 "B.Adhes" user "B.Adhesive")
		(13 "F.Paste" user "Package Geometry/Pastemask Top")
		(15 "B.Paste" user "Package Geometry/Pastemask Bottom")
		(5 "F.SilkS" user "Ref Des/Silkscreen Top")
		(7 "B.SilkS" user "Ref Des/Silkscreen Bottom")
		(1 "F.Mask" user "Board Geometry/Soldermask Top")
		(3 "B.Mask" user "Board Geometry/Soldermask Bottom")
		(17 "Dwgs.User" user "User.Drawings")
		(19 "Cmts.User" user "User.Comments")
		(21 "Eco1.User" user "User.Eco1")
		(23 "Eco2.User" user "User.Eco2")
		(25 "Edge.Cuts" user "Board Geometry/Outline")
		(27 "Margin" user)
		(31 "F.CrtYd" user "Package Geometry/Place Bound Top")
		(29 "B.CrtYd" user "Package Geometry/Place Bound Bottom")
		(35 "F.Fab" user "Ref Des/Assembly Top")
		(33 "B.Fab" user "Ref Des/Assembly Bottom")
	)
	(footprint ""
		(layer "F.Cu")
		(at 192.898268 -426.355002)
		(property "Reference" "U290"
			(at -1.524508 2.771902 0)
			(unlocked yes)
			(layer "F.SilkS")
			(effects
				(font
					(size 0.7874 0.5842)
					(thickness 0.1524)
				)
				(justify left)
			)
		)
		(property "Value" ""
			(at 0 0 0)
			(layer "F.Fab")
			(effects
				(font
					(size 1.27 1.27)
				)
			)
		)
		(duplicate_pad_numbers_are_jumpers no)
		(fp_line
			(start -1.603248 -1.500124)
			(end 1.603248 -1.500124)
			(stroke
				(width 0.1524)
				(type default)
			)
			(layer "F.SilkS")
		)
		(fp_line
			(start -1.603248 1.500124)
			(end -1.603248 -1.500124)
			(stroke
				(width 0.1524)
				(type default)
			)
			(layer "F.SilkS")
		)
		(fp_line
			(start 1.603248 -1.500124)
			(end 1.603248 1.500124)
			(stroke
				(width 0.1524)
				(type default)
			)
			(layer "F.SilkS")
		)
		(fp_line
			(start 1.603248 1.500124)
			(end -1.603248 1.500124)
			(stroke
				(width 0.1524)
				(type default)
			)
			(layer "F.SilkS")
		)
		(fp_line
			(start -1.249934 -1.169924)
			(end -1.249934 -0.729996)
			(stroke
				(width 0.1)
				(type default)
			)
			(layer "F.Fab")
		)
		(fp_line
			(start -1.249934 -0.729996)
			(end -0.6985 -0.729996)
			(stroke
				(width 0.1)
				(type default)
			)
			(layer "F.Fab")
		)
		(fp_line
			(start -1.249934 0.729996)
			(end -1.249934 1.169924)
			(stroke
				(width 0.1)
				(type default)
			)
			(layer "F.Fab")
		)
		(fp_line
			(start -1.249934 1.169924)
			(end -0.700024 1.169924)
			(stroke
				(width 0.1)
				(type default)
			)
			(layer "F.Fab")
		)
		(fp_line
			(start -0.700024 -1.500124)
			(end -0.700024 -1.169924)
			(stroke
				(width 0.1)
				(type default)
			)
			(layer "F.Fab")
		)
		(fp_line
			(start -0.700024 -1.169924)
			(end -1.249934 -1.169924)
			(stroke
				(width 0.1)
				(type default)
			)
			(layer "F.Fab")
		)
		(fp_line
			(start -0.700024 1.169924)
			(end -0.700024 1.500124)
			(stroke
				(width 0.1)
				(type default)
			)
			(layer "F.Fab")
		)
		(fp_line
			(start -0.700024 1.500124)
			(end 0.700024 1.500124)
			(stroke
				(width 0.1)
				(type default)
			)
			(layer "F.Fab")
		)
		(fp_line
			(start -0.6985 -0.729996)
			(end -0.6985 0.729996)
			(stroke
				(width 0.1)
				(type default)
			)
			(layer "F.Fab")
		)
		(fp_line
			(start -0.6985 0.729996)
			(end -1.249934 0.729996)
			(stroke
				(width 0.1)
				(type default)
			)
			(layer "F.Fab")
		)
		(fp_line
			(start 0.700024 -1.500124)
			(end -0.700024 -1.500124)
			(stroke
				(width 0.1)
				(type default)
			)
			(layer "F.Fab")
		)
		(fp_line
			(start 0.700024 -0.219964)
			(end 0.700024 -1.500124)
			(stroke
				(width 0.1)
				(type default)
			)
			(layer "F.Fab")
		)
		(fp_line
			(start 0.700024 0.219964)
			(end 1.249934 0.219964)
			(stroke
				(width 0.1)
				(type default)
			)
			(layer "F.Fab")
		)
		(fp_line
			(start 0.700024 1.500124)
			(end 0.700024 0.219964)
			(stroke
				(width 0.1)
				(type default)
			)
			(layer "F.Fab")
		)
		(fp_line
			(start 1.249934 -0.219964)
			(end 0.700024 -0.219964)
			(stroke
				(width 0.1)
				(type default)
			)
			(layer "F.Fab")
		)
		(fp_line
			(start 1.249934 0.219964)
			(end 1.249934 -0.219964)
			(stroke
				(width 0.1)
				(type default)
			)
			(layer "F.Fab")
		)
		(fp_rect
			(start 0.700024 1.500124)
			(end -0.700024 -1.500124)
			(stroke
				(width 0)
				(type default)
			)
			(fill no)
			(layer "F.Fab")
		)
		(pad "D" smd rect
			(at 0.999998 0 270)
			(size 0.8128 0.9144)
			(layers "F.Cu" "F.Mask" "F.Paste")
			(net "HSC_EN")
		)
		(pad "G" smd rect
			(at -0.999998 -0.94996 270)
			(size 0.8128 0.9144)
			(layers "F.Cu" "F.Mask" "F.Paste")
			(net "PDB_PRSNT_N")
		)
		(pad "S" smd rect
			(at -0.999998 0.94996 270)
			(size 0.8128 0.9144)
			(layers "F.Cu" "F.Mask" "F.Paste")
			(net "GND")
		)
	)
)
